# S9S_MB_2U (Grand Teton) — schematic netlist excerpt (pin names and nets, part order shuffled) for the footprints in the layout excerpt that follows; sources: Cadence DE-HDL packaged netlist, KiCad conversion of 03242023_DA0F0TMBIJ0_F0T_Motherboard_J_brd_V01_OCP.brd

R1496  Q_RES  10K 1% CHIP  pkg 0402LF  page 200 : A = P3V3_AUX ; B = FM_PCH_DFXTESTMODE
R1827  Q_RES  33.2 1% CHIP  pkg 0402LF  page 183 : A = USB_OC1_REAR_R_N ; B = USB_OC1_REAR_N

(kicad_pcb
	(version 20260206)
	(generator "pcbnew")
	(generator_version "10.0")
	(general
		(thickness 1.6)
		(legacy_teardrops no)
	)
	(paper "A4")
	(title_block
		(title "03242023_DA0F0TMBIJ0_F0T_Motherboard_J_brd_V01_OCP.brd")
		(comment 1 "Grand Teton / footprints 897-898 of 6105")
	)
	(layers
		(0 "F.Cu" signal "TOP")
		(4 "In1.Cu" signal "GND")
		(6 "In2.Cu" signal "IN1")
		(8 "In3.Cu" signal "GND1")
		(10 "In4.Cu" signal "IN2")
		(12 "In5.Cu" signal "GND2")
		(14 "In6.Cu" signal "IN3")
		(16 "In7.Cu" signal "GND3")
		(18 "In8.Cu" signal "VCC")
		(20 "In9.Cu" signal "VCC1")
		(22 "In10.Cu" signal "GND4")
		(24 "In11.Cu" signal "IN4")
		(26 "In12.Cu" signal "GND5")
		(28 "In13.Cu" signal "IN5")
		(30 "In14.Cu" signal "GND6")
		(32 "In15.Cu" signal "IN6")
		(34 "In16.Cu" signal "GND7")
		(2 "B.Cu" signal "BOTTOM")
		(9 "F.Adhes" user "F.Adhesive")
		(11 "B.Adhes" user "B.Adhesive")
		(13 "F.Paste" user "Package Geometry/Pastemask Top")
		(15 "B.Paste" user "Package Geometry/Pastemask Bottom")
		(5 "F.SilkS" user "Ref Des/Silkscreen Top")
		(7 "B.SilkS" user "Ref Des/Silkscreen Bottom")
		(1 "F.Mask" user "Board Geometry/Soldermask Top")
		(3 "B.Mask" user "Board Geometry/Soldermask Bottom")
		(17 "Dwgs.User" user "User.Drawings")
		(19 "Cmts.User" user "User.Comments")
		(21 "Eco1.User" user "User.Eco1")
		(23 "Eco2.User" user "User.Eco2")
		(25 "Edge.Cuts" user "Board Geometry/Outline")
		(27 "Margin" user)
		(31 "F.CrtYd" user "Package Geometry/Place Bound Top")
		(29 "B.CrtYd" user "Package Geometry/Place Bound Bottom")
		(35 "F.Fab" user "Ref Des/Assembly Top")
		(33 "B.Fab" user "Ref Des/Assembly Bottom")
	)
	(footprint ""
		(layer "F.Cu")
		(at 348.044008 -20.602194)
		(property "Reference" "R1827"
			(at 0 0 0)
			(layer "F.SilkS")
			(hide yes)
			(effects
				(font
					(size 1.27 1.27)
				)
			)
		)
		(property "Value" ""
			(at 0 0 0)
			(layer "F.Fab")
			(effects
				(font
					(size 1.27 1.27)
				)
			)
		)
		(duplicate_pad_numbers_are_jumpers no)
		(fp_line
			(start -0.7874 -0.4064)
			(end 0.7874 -0.4064)
			(stroke
				(width 0.1524)
				(type default)
			)
			(layer "F.SilkS")
		)
		(fp_line
			(start -0.7874 0.4064)
			(end -0.7874 -0.4064)
			(stroke
				(width 0.1524)
				(type default)
			)
			(layer "F.SilkS")
		)
		(fp_line
			(start 0.7874 -0.4064)
			(end 0.7874 0.4064)
			(stroke
				(width 0.1524)
				(type default)
			)
			(layer "F.SilkS")
		)
		(fp_line
			(start 0.7874 0.4064)
			(end -0.7874 0.4064)
			(stroke
				(width 0.1524)
				(type default)
			)
			(layer "F.SilkS")
		)
		(fp_line
			(start -0.67945 -0.305054)
			(end -0.12065 -0.305054)
			(stroke
				(width 0.1)
				(type default)
			)
			(layer "F.Fab")
		)
		(fp_line
			(start -0.67945 0.3048)
			(end -0.67945 -0.305054)
			(stroke
				(width 0.1)
				(type default)
			)
			(layer "F.Fab")
		)
		(fp_line
			(start -0.12065 -0.305054)
			(end -0.12065 -0.2794)
			(stroke
				(width 0.1)
				(type default)
			)
			(layer "F.Fab")
		)
		(fp_line
			(start -0.12065 -0.2794)
			(end 0.12065 -0.2794)
			(stroke
				(width 0.1)
				(type default)
			)
			(layer "F.Fab")
		)
		(fp_line
			(start -0.12065 0.2794)
			(end -0.12065 0.3048)
			(stroke
				(width 0.1)
				(type default)
			)
			(layer "F.Fab")
		)
		(fp_line
			(start -0.12065 0.3048)
			(end -0.67945 0.3048)
			(stroke
				(width 0.1)
				(type default)
			)
			(layer "F.Fab")
		)
		(fp_line
			(start 0.120396 0.2794)
			(end -0.12065 0.2794)
			(stroke
				(width 0.1)
				(type default)
			)
			(layer "F.Fab")
		)
		(fp_line
			(start 0.120396 0.3048)
			(end 0.120396 0.2794)
			(stroke
				(width 0.1)
				(type default)
			)
			(layer "F.Fab")
		)
		(fp_line
			(start 0.12065 -0.3048)
			(end 0.67945 -0.3048)
			(stroke
				(width 0.1)
				(type default)
			)
			(layer "F.Fab")
		)
		(fp_line
			(start 0.12065 -0.2794)
			(end 0.12065 -0.3048)
			(stroke
				(width 0.1)
				(type default)
			)
			(layer "F.Fab")
		)
		(fp_line
			(start 0.67945 -0.3048)
			(end 0.67945 0.3048)
			(stroke
				(width 0.1)
				(type default)
			)
			(layer "F.Fab")
		)
		(fp_line
			(start 0.67945 0.3048)
			(end 0.120396 0.3048)
			(stroke
				(width 0.1)
				(type default)
			)
			(layer "F.Fab")
		)
		(pad "1" smd circle
			(at -0.40005 0)
			(size 0 0)
			(layers "F.Cu" "F.Mask" "F.Paste")
			(net "USB_OC1_REAR_R_N")
		)
		(pad "2" smd circle
			(at 0.40005 0)
			(size 0 0)
			(layers "F.Cu" "F.Mask" "F.Paste")
			(net "USB_OC1_REAR_N")
		)
	)
	(footprint ""
		(layer "F.Cu")
		(at 317.396622 -55.794148)
		(property "Reference" "R1496"
			(at 0 0 0)
			(layer "F.SilkS")
			(hide yes)
			(effects
				(font
					(size 1.27 1.27)
				)
			)
		)
		(property "Value" ""
			(at 0 0 0)
			(layer "F.Fab")
			(effects
				(font
					(size 1.27 1.27)
				)
			)
		)
		(duplicate_pad_numbers_are_jumpers no)
		(fp_line
			(start -0.7874 -0.4064)
			(end 0.7874 -0.4064)
			(stroke
				(width 0.1524)
				(type default)
			)
			(layer "F.SilkS")
		)
		(fp_line
			(start -0.7874 0.4064)
			(end -0.7874 -0.4064)
			(stroke
				(width 0.1524)
				(type default)
			)
			(layer "F.SilkS")
		)
		(fp_line
			(start 0.7874 -0.4064)
			(end 0.7874 0.4064)
			(stroke
				(width 0.1524)
				(type default)
			)
			(layer "F.SilkS")
		)
		(fp_line
			(start 0.7874 0.4064)
			(end -0.7874 0.4064)
			(stroke
				(width 0.1524)
				(type default)
			)
			(layer "F.SilkS")
		)
		(fp_line
			(start -0.67945 -0.305054)
			(end -0.12065 -0.305054)
			(stroke
				(width 0.1)
				(type default)
			)
			(layer "F.Fab")
		)
		(fp_line
			(start -0.67945 0.3048)
			(end -0.67945 -0.305054)
			(stroke
				(width 0.1)
				(type default)
			)
			(layer "F.Fab")
		)
		(fp_line
			(start -0.12065 -0.305054)
			(end -0.12065 -0.2794)
			(stroke
				(width 0.1)
				(type default)
			)
			(layer "F.Fab")
		)
		(fp_line
			(start -0.12065 -0.2794)
			(end 0.12065 -0.2794)
			(stroke
				(width 0.1)
				(type default)
			)
			(layer "F.Fab")
		)
		(fp_line
			(start -0.12065 0.2794)
			(end -0.12065 0.3048)
			(stroke
				(width 0.1)
				(type default)
			)
			(layer "F.Fab")
		)
		(fp_line
			(start -0.12065 0.3048)
			(end -0.67945 0.3048)
			(stroke
				(width 0.1)
				(type default)
			)
			(layer "F.Fab")
		)
		(fp_line
			(start 0.120396 0.2794)
			(end -0.12065 0.2794)
			(stroke
				(width 0.1)
				(type default)
			)
			(layer "F.Fab")
		)
		(fp_line
			(start 0.120396 0.3048)
			(end 0.120396 0.2794)
			(stroke
				(width 0.1)
				(type default)
			)
			(layer "F.Fab")
		)
		(fp_line
			(start 0.12065 -0.3048)
			(end 0.67945 -0.3048)
			(stroke
				(width 0.1)
				(type default)
			)
			(layer "F.Fab")
		)
		(fp_line
			(start 0.12065 -0.2794)
			(end 0.12065 -0.3048)
			(stroke
				(width 0.1)
				(type default)
			)
			(layer "F.Fab")
		)
		(fp_line
			(start 0.67945 -0.3048)
			(end 0.67945 0.3048)
			(stroke
				(width 0.1)
				(type default)
			)
			(layer "F.Fab")
		)
		(fp_line
			(start 0.67945 0.3048)
			(end 0.120396 0.3048)
			(stroke
				(width 0.1)
				(type default)
			)
			(layer "F.Fab")
		)
		(pad "1" smd circle
			(at -0.40005 0)
			(size 0 0)
			(layers "F.Cu" "F.Mask" "F.Paste")
			(net "P3V3_AUX")
		)
		(pad "2" smd circle
			(at 0.40005 0)
			(size 0 0)
			(layers "F.Cu" "F.Mask" "F.Paste")
			(net "FM_PCH_DFXTESTMODE")
		)
	)
)
